(kicad_pcb
	(version 20260206)
	(generator "pcbnew")
	(generator_version "10.0")
	(general
		(thickness 1.6)
		(legacy_teardrops no)
	)
	(paper "A4")
	(title_block
		(title "Bryce Canyon_IOM_IOC_16318-2_OCP.brd")
		(comment 1 "Bryce Canyon / footprints 179-187 of 1605")
	)
	(layers
		(0 "F.Cu" signal "TOP")
		(4 "In1.Cu" signal "L2GND")
		(6 "In2.Cu" signal "L3")
		(8 "In3.Cu" signal "L4VCC")
		(10 "In4.Cu" signal "L5VCC")
		(12 "In5.Cu" signal "L6")
		(14 "In6.Cu" signal "L7GND")
		(2 "B.Cu" signal "BOTTOM")
		(9 "F.Adhes" user "F.Adhesive")
		(11 "B.Adhes" user "B.Adhesive")
		(13 "F.Paste" user "Package Geometry/Pastemask Top")
		(15 "B.Paste" user "Package Geometry/Pastemask Bottom")
		(5 "F.SilkS" user "Ref Des/Silkscreen Top")
		(7 "B.SilkS" user "Ref Des/Silkscreen Bottom")
		(1 "F.Mask" user "Board Geometry/Soldermask Top")
		(3 "B.Mask" user "Board Geometry/Soldermask Bottom")
		(17 "Dwgs.User" user "User.Drawings")
		(19 "Cmts.User" user "User.Comments")
		(21 "Eco1.User" user "User.Eco1")
		(23 "Eco2.User" user "User.Eco2")
		(25 "Edge.Cuts" user "Board Geometry/Outline")
		(27 "Margin" user)
		(31 "F.CrtYd" user "Package Geometry/Place Bound Top")
		(29 "B.CrtYd" user "Package Geometry/Place Bound Bottom")
		(35 "F.Fab" user "Ref Des/Assembly Top")
		(33 "B.Fab" user "Ref Des/Assembly Bottom")
	)
	(footprint ""
		(layer "F.Cu")
		(at 24.042116 -162.3441 90)
		(property "Reference" "C225"
			(at 0 0 90)
			(layer "F.SilkS")
			(hide yes)
			(effects
				(font
					(size 1.27 1.27)
				)
			)
		)
		(property "Value" "SC10U6D3V5KX-4GP"
			(at -0.0762 -6.1214 90)
			(unlocked yes)
			(layer "F.Fab")
			(hide yes)
			(effects
				(font
					(size 1.016 1.016)
					(thickness 0.1524)
				)
			)
		)
		(property "Device Type" "C805H58"
			(at -0.0762 -8.1534 90)
			(unlocked yes)
			(layer "F.Fab")
			(hide yes)
			(effects
				(font
					(size 1.016 1.016)
					(thickness 0.1524)
				)
			)
		)
		(duplicate_pad_numbers_are_jumpers no)
		(fp_line
			(start 0.635 0)
			(end -0.635 0)
			(stroke
				(width 0.508)
				(type default)
			)
			(layer "F.SilkS")
		)
		(fp_rect
			(start -0.9652 1.778)
			(end 0.9652 -1.778)
			(stroke
				(width 0)
				(type default)
			)
			(fill no)
			(layer "F.CrtYd")
		)
		(fp_poly
			(pts
				(xy -0.9652 -1.778) (xy 0.9652 -1.778) (xy 0.9652 1.778) (xy -0.9652 1.778)
			)
			(stroke
				(width 0)
				(type default)
			)
			(fill no)
			(layer "F.Fab")
		)
		(pad "1" smd rect
			(at 0 -0.9652 90)
			(size 1.397 1.143)
			(layers "F.Cu" "F.Mask" "F.Paste")
			(net "TPS74801_P1V2_STBY_OUT")
		)
		(pad "2" smd rect
			(at 0 0.9652 90)
			(size 1.397 1.143)
			(layers "F.Cu" "F.Mask" "F.Paste")
			(net "GND")
		)
	)
	(footprint ""
		(layer "F.Cu")
		(at 23.2537 -167.221916 180)
		(property "Reference" "C224"
			(at 0 0 180)
			(layer "F.SilkS")
			(hide yes)
			(effects
				(font
					(size 1.27 1.27)
				)
			)
		)
		(property "Value" "SC10U6D3V5KX-4GP"
			(at -0.0762 -6.1214 180)
			(unlocked yes)
			(layer "F.Fab")
			(hide yes)
			(effects
				(font
					(size 1.016 1.016)
					(thickness 0.1524)
				)
			)
		)
		(property "Device Type" "C805H58"
			(at -0.0762 -8.1534 180)
			(unlocked yes)
			(layer "F.Fab")
			(hide yes)
			(effects
				(font
					(size 1.016 1.016)
					(thickness 0.1524)
				)
			)
		)
		(duplicate_pad_numbers_are_jumpers no)
		(fp_line
			(start 0.635 0)
			(end -0.635 0)
			(stroke
				(width 0.508)
				(type default)
			)
			(layer "F.SilkS")
		)
		(fp_rect
			(start -0.9652 1.778)
			(end 0.9652 -1.778)
			(stroke
				(width 0)
				(type default)
			)
			(fill no)
			(layer "F.CrtYd")
		)
		(fp_poly
			(pts
				(xy -0.9652 -1.778) (xy 0.9652 -1.778) (xy 0.9652 1.778) (xy -0.9652 1.778)
			)
			(stroke
				(width 0)
				(type default)
			)
			(fill no)
			(layer "F.Fab")
		)
		(pad "1" smd rect
			(at 0 -0.9652 180)
			(size 1.397 1.143)
			(layers "F.Cu" "F.Mask" "F.Paste")
			(net "TPS74801_P1V2_STBY_OUT")
		)
		(pad "2" smd rect
			(at 0 0.9652 180)
			(size 1.397 1.143)
			(layers "F.Cu" "F.Mask" "F.Paste")
			(net "GND")
		)
	)
	(footprint ""
		(layer "F.Cu")
		(at 44.9834 -161.3662 180)
		(property "Reference" "R187"
			(at 0 0 180)
			(layer "F.SilkS")
			(hide yes)
			(effects
				(font
					(size 1.27 1.27)
				)
			)
		)
		(property "Value" "2K2R2F-GP"
			(at 0.064008 -3.993896 180)
			(unlocked yes)
			(layer "F.Fab")
			(hide yes)
			(effects
				(font
					(size 1.016 1.016)
					(thickness 0.1524)
				)
			)
		)
		(property "Device Type" "R402H16"
			(at 0.064008 -5.517896 180)
			(unlocked yes)
			(layer "F.Fab")
			(hide yes)
			(effects
				(font
					(size 1.016 1.016)
					(thickness 0.1524)
				)
			)
		)
		(duplicate_pad_numbers_are_jumpers no)
		(fp_line
			(start 0.508 -0.9398)
			(end -0.508 -0.9398)
			(stroke
				(width 0.1524)
				(type default)
			)
			(layer "F.SilkS")
		)
		(fp_line
			(start -0.508 -0.9398)
			(end -0.508 0.9398)
			(stroke
				(width 0.1524)
				(type default)
			)
			(layer "F.SilkS")
		)
		(fp_rect
			(start -0.508 0.9398)
			(end 0.508 -0.9398)
			(stroke
				(width 0)
				(type default)
			)
			(fill no)
			(layer "F.CrtYd")
		)
		(fp_rect
			(start -0.508 0.9398)
			(end 0.508 -0.9398)
			(stroke
				(width 0)
				(type default)
			)
			(fill no)
			(layer "F.Fab")
		)
		(pad "1" smd custom
			(at 0 -0.4445 180)
			(size 0.1397 0.1397)
			(layers "F.Cu" "F.Mask" "F.Paste")
			(net "I2C_M2_1_SCL")
			(options
				(clearance outline)
				(anchor circle)
			)
			(primitives
				(gr_poly
					(pts
						(arc
							(start -0.1778 -0.2794)
							(mid -0.249642 -0.249642)
							(end -0.2794 -0.1778)
						)
						(arc
							(start -0.2794 0.1778)
							(mid -0.249642 0.249642)
							(end -0.1778 0.2794)
						)
						(arc
							(start 0.1778 0.2794)
							(mid 0.249642 0.249642)
							(end 0.2794 0.1778)
						)
						(arc
							(start 0.2794 -0.1778)
							(mid 0.249642 -0.249642)
							(end 0.1778 -0.2794)
						)
					)
					(width 0)
					(fill yes)
				)
			)
		)
		(pad "2" smd custom
			(at 0 0.4445 180)
			(size 0.1397 0.1397)
			(layers "F.Cu" "F.Mask" "F.Paste")
			(net "P3V3_STBY")
			(options
				(clearance outline)
				(anchor circle)
			)
			(primitives
				(gr_poly
					(pts
						(arc
							(start -0.1778 -0.2794)
							(mid -0.249642 -0.249642)
							(end -0.2794 -0.1778)
						)
						(arc
							(start -0.2794 0.1778)
							(mid -0.249642 0.249642)
							(end -0.1778 0.2794)
						)
						(arc
							(start 0.1778 0.2794)
							(mid 0.249642 0.249642)
							(end 0.2794 0.1778)
						)
						(arc
							(start 0.2794 -0.1778)
							(mid 0.249642 -0.249642)
							(end 0.1778 -0.2794)
						)
					)
					(width 0)
					(fill yes)
				)
			)
		)
	)
	(footprint ""
		(layer "F.Cu")
		(at 40.824658 -131.704588 180)
		(property "Reference" "R376"
			(at 0 0 180)
			(layer "F.SilkS")
			(hide yes)
			(effects
				(font
					(size 1.27 1.27)
				)
			)
		)
		(property "Value" "4K7R2F-GP"
			(at 0.064008 -3.993896 180)
			(unlocked yes)
			(layer "F.Fab")
			(hide yes)
			(effects
				(font
					(size 1.016 1.016)
					(thickness 0.1524)
				)
			)
		)
		(property "Device Type" "R402H16"
			(at 0.064008 -5.517896 180)
			(unlocked yes)
			(layer "F.Fab")
			(hide yes)
			(effects
				(font
					(size 1.016 1.016)
					(thickness 0.1524)
				)
			)
		)
		(duplicate_pad_numbers_are_jumpers no)
		(fp_line
			(start 0.508 -0.9398)
			(end -0.508 -0.9398)
			(stroke
				(width 0.1524)
				(type default)
			)
			(layer "F.SilkS")
		)
		(fp_line
			(start -0.508 -0.9398)
			(end -0.508 0.9398)
			(stroke
				(width 0.1524)
				(type default)
			)
			(layer "F.SilkS")
		)
		(fp_rect
			(start -0.508 0.9398)
			(end 0.508 -0.9398)
			(stroke
				(width 0)
				(type default)
			)
			(fill no)
			(layer "F.CrtYd")
		)
		(fp_rect
			(start -0.508 0.9398)
			(end 0.508 -0.9398)
			(stroke
				(width 0)
				(type default)
			)
			(fill no)
			(layer "F.Fab")
		)
		(pad "1" smd custom
			(at 0 -0.4445 180)
			(size 0.1397 0.1397)
			(layers "F.Cu" "F.Mask" "F.Paste")
			(net "P3V3_STBY")
			(options
				(clearance outline)
				(anchor circle)
			)
			(primitives
				(gr_poly
					(pts
						(arc
							(start -0.1778 -0.2794)
							(mid -0.249642 -0.249642)
							(end -0.2794 -0.1778)
						)
						(arc
							(start -0.2794 0.1778)
							(mid -0.249642 0.249642)
							(end -0.1778 0.2794)
						)
						(arc
							(start 0.1778 0.2794)
							(mid 0.249642 0.249642)
							(end 0.2794 0.1778)
						)
						(arc
							(start 0.2794 -0.1778)
							(mid 0.249642 -0.249642)
							(end 0.1778 -0.2794)
						)
					)
					(width 0)
					(fill yes)
				)
			)
		)
		(pad "2" smd custom
			(at 0 0.4445 180)
			(size 0.1397 0.1397)
			(layers "F.Cu" "F.Mask" "F.Paste")
			(net "BMC_GPIOZ4")
			(options
				(clearance outline)
				(anchor circle)
			)
			(primitives
				(gr_poly
					(pts
						(arc
							(start -0.1778 -0.2794)
							(mid -0.249642 -0.249642)
							(end -0.2794 -0.1778)
						)
						(arc
							(start -0.2794 0.1778)
							(mid -0.249642 0.249642)
							(end -0.1778 0.2794)
						)
						(arc
							(start 0.1778 0.2794)
							(mid 0.249642 0.249642)
							(end 0.2794 0.1778)
						)
						(arc
							(start 0.2794 -0.1778)
							(mid 0.249642 -0.249642)
							(end 0.1778 -0.2794)
						)
					)
					(width 0)
					(fill yes)
				)
			)
		)
	)
	(footprint ""
		(layer "F.Cu")
		(at 169.037 -174.9552 -90)
		(property "Reference" "C166"
			(at 0 0 270)
			(layer "F.SilkS")
			(hide yes)
			(effects
				(font
					(size 1.27 1.27)
				)
			)
		)
		(property "Value" "SC10U16V5KX-7-GP-U"
			(at -0.0762 -6.1214 270)
			(unlocked yes)
			(layer "F.Fab")
			(hide yes)
			(effects
				(font
					(size 1.016 1.016)
					(thickness 0.1524)
				)
			)
		)
		(property "Device Type" "C805H58"
			(at -0.0762 -8.1534 270)
			(unlocked yes)
			(layer "F.Fab")
			(hide yes)
			(effects
				(font
					(size 1.016 1.016)
					(thickness 0.1524)
				)
			)
		)
		(duplicate_pad_numbers_are_jumpers no)
		(fp_line
			(start 0.635 0)
			(end -0.635 0)
			(stroke
				(width 0.508)
				(type default)
			)
			(layer "F.SilkS")
		)
		(fp_rect
			(start -0.9652 1.778)
			(end 0.9652 -1.778)
			(stroke
				(width 0)
				(type default)
			)
			(fill no)
			(layer "F.CrtYd")
		)
		(fp_poly
			(pts
				(xy -0.9652 -1.778) (xy 0.9652 -1.778) (xy 0.9652 1.778) (xy -0.9652 1.778)
			)
			(stroke
				(width 0)
				(type default)
			)
			(fill no)
			(layer "F.Fab")
		)
		(pad "1" smd rect
			(at 0 -0.9652 270)
			(size 1.397 1.143)
			(layers "F.Cu" "F.Mask" "F.Paste")
			(net "P5V_STBY")
		)
		(pad "2" smd rect
			(at 0 0.9652 270)
			(size 1.397 1.143)
			(layers "F.Cu" "F.Mask" "F.Paste")
			(net "GND")
		)
	)
	(footprint ""
		(layer "F.Cu")
		(at 42.8752 -159.6136)
		(property "Reference" "TP14"
			(at 0 0 0)
			(layer "F.SilkS")
			(hide yes)
			(effects
				(font
					(size 1.27 1.27)
				)
			)
		)
		(property "Value" "TPAD28-2-GP"
			(at -0.0127 -1.6637 0)
			(unlocked yes)
			(layer "F.Fab")
			(hide yes)
			(effects
				(font
					(size 1.016 1.016)
					(thickness 0.1524)
				)
			)
		)
		(property "Device Type" "TPAD28"
			(at -0.0127 -3.1877 0)
			(unlocked yes)
			(layer "F.Fab")
			(hide yes)
			(effects
				(font
					(size 1.016 1.016)
					(thickness 0.1524)
				)
			)
		)
		(duplicate_pad_numbers_are_jumpers no)
		(fp_poly
			(pts
				(arc
					(start 0.3556 0)
					(mid -0.3556 0)
					(end 0.3556 0)
				)
			)
			(stroke
				(width 0)
				(type default)
			)
			(fill no)
			(layer "F.CrtYd")
		)
		(fp_poly
			(pts
				(arc
					(start 0.6096 0)
					(mid -0.6096 0)
					(end 0.6096 0)
				)
			)
			(stroke
				(width 0)
				(type default)
			)
			(fill no)
			(layer "F.Fab")
		)
		(pad "1" smd circle
			(at 0 0)
			(size 0.7112 0.7112)
			(layers "F.Cu" "F.Mask" "F.Paste")
			(net "I2C_M2_1_SDA")
		)
	)
	(footprint ""
		(layer "F.Cu")
		(at 204.3684 -49.9618)
		(property "Reference" "TP144"
			(at 0 0 0)
			(layer "F.SilkS")
			(hide yes)
			(effects
				(font
					(size 1.27 1.27)
				)
			)
		)
		(property "Value" "TPAD28-2-GP"
			(at -0.0127 -1.6637 0)
			(unlocked yes)
			(layer "F.Fab")
			(hide yes)
			(effects
				(font
					(size 1.016 1.016)
					(thickness 0.1524)
				)
			)
		)
		(property "Device Type" "TPAD28"
			(at -0.0127 -3.1877 0)
			(unlocked yes)
			(layer "F.Fab")
			(hide yes)
			(effects
				(font
					(size 1.016 1.016)
					(thickness 0.1524)
				)
			)
		)
		(duplicate_pad_numbers_are_jumpers no)
		(fp_poly
			(pts
				(arc
					(start 0.3556 0)
					(mid -0.3556 0)
					(end 0.3556 0)
				)
			)
			(stroke
				(width 0)
				(type default)
			)
			(fill no)
			(layer "F.CrtYd")
		)
		(fp_poly
			(pts
				(arc
					(start 0.6096 0)
					(mid -0.6096 0)
					(end 0.6096 0)
				)
			)
			(stroke
				(width 0)
				(type default)
			)
			(fill no)
			(layer "F.Fab")
		)
		(pad "1" smd circle
			(at 0 0)
			(size 0.7112 0.7112)
			(layers "F.Cu" "F.Mask" "F.Paste")
			(net "ICE1_TRST#")
		)
	)
	(footprint ""
		(layer "F.Cu")
		(at 182.0291 -48.1457)
		(property "Reference" "R670"
			(at 0 0 0)
			(layer "F.SilkS")
			(hide yes)
			(effects
				(font
					(size 1.27 1.27)
				)
			)
		)
		(property "Value" "10KR2F-2-GP"
			(at 0.064008 -3.993896 0)
			(unlocked yes)
			(layer "F.Fab")
			(hide yes)
			(effects
				(font
					(size 1.016 1.016)
					(thickness 0.1524)
				)
			)
		)
		(property "Device Type" "R402H16"
			(at 0.064008 -5.517896 0)
			(unlocked yes)
			(layer "F.Fab")
			(hide yes)
			(effects
				(font
					(size 1.016 1.016)
					(thickness 0.1524)
				)
			)
		)
		(duplicate_pad_numbers_are_jumpers no)
		(fp_line
			(start -0.508 -0.9398)
			(end -0.508 0.9398)
			(stroke
				(width 0.1524)
				(type default)
			)
			(layer "F.SilkS")
		)
		(fp_line
			(start 0.508 -0.9398)
			(end -0.508 -0.9398)
			(stroke
				(width 0.1524)
				(type default)
			)
			(layer "F.SilkS")
		)
		(fp_rect
			(start -0.508 0.9398)
			(end 0.508 -0.9398)
			(stroke
				(width 0)
				(type default)
			)
			(fill no)
			(layer "F.CrtYd")
		)
		(fp_rect
			(start -0.508 0.9398)
			(end 0.508 -0.9398)
			(stroke
				(width 0)
				(type default)
			)
			(fill no)
			(layer "F.Fab")
		)
		(pad "1" smd custom
			(at 0 -0.4445)
			(size 0.1397 0.1397)
			(layers "F.Cu" "F.Mask" "F.Paste")
			(net "XM_ADDR_4")
			(options
				(clearance outline)
				(anchor circle)
			)
			(primitives
				(gr_poly
					(pts
						(arc
							(start -0.1778 -0.2794)
							(mid -0.249642 -0.249642)
							(end -0.2794 -0.1778)
						)
						(arc
							(start -0.2794 0.1778)
							(mid -0.249642 0.249642)
							(end -0.1778 0.2794)
						)
						(arc
							(start 0.1778 0.2794)
							(mid 0.249642 0.249642)
							(end 0.2794 0.1778)
						)
						(arc
							(start 0.2794 -0.1778)
							(mid 0.249642 -0.249642)
							(end 0.1778 -0.2794)
						)
					)
					(width 0)
					(fill yes)
				)
			)
		)
		(pad "2" smd custom
			(at 0 0.4445)
			(size 0.1397 0.1397)
			(layers "F.Cu" "F.Mask" "F.Paste")
			(net "GND")
			(options
				(clearance outline)
				(anchor circle)
			)
			(primitives
				(gr_poly
					(pts
						(arc
							(start -0.1778 -0.2794)
							(mid -0.249642 -0.249642)
							(end -0.2794 -0.1778)
						)
						(arc
							(start -0.2794 0.1778)
							(mid -0.249642 0.249642)
							(end -0.1778 0.2794)
						)
						(arc
							(start 0.1778 0.2794)
							(mid 0.249642 0.249642)
							(end 0.2794 0.1778)
						)
						(arc
							(start 0.2794 -0.1778)
							(mid 0.249642 -0.249642)
							(end 0.1778 -0.2794)
						)
					)
					(width 0)
					(fill yes)
				)
			)
		)
	)
	(footprint ""
		(layer "F.Cu")
		(at 71.7804 -173.7106 180)
		(property "Reference" "C78"
			(at 0 0 180)
			(layer "F.SilkS")
			(hide yes)
			(effects
				(font
					(size 1.27 1.27)
				)
			)
		)
		(property "Value" "SCD1U16V2KX-3GP"
			(at 1.1811 -2.7051 180)
			(unlocked yes)
			(layer "F.Fab")
			(hide yes)
			(effects
				(font
					(size 1.016 1.016)
					(thickness 0.1524)
				)
			)
		)
		(property "Device Type" "C402H22"
			(at 1.1811 -4.2291 180)
			(unlocked yes)
			(layer "F.Fab")
			(hide yes)
			(effects
				(font
					(size 1.016 1.016)
					(thickness 0.1524)
				)
			)
		)
		(duplicate_pad_numbers_are_jumpers no)
		(fp_rect
			(start -0.4318 0.9525)
			(end 0.4318 -0.9525)
			(stroke
				(width 0)
				(type default)
			)
			(fill no)
			(layer "F.CrtYd")
		)
		(fp_rect
			(start -0.4318 0.9525)
			(end 0.4318 -0.9525)
			(stroke
				(width 0)
				(type default)
			)
			(fill no)
			(layer "F.Fab")
		)
		(pad "1" smd custom
			(at 0 -0.4445 180)
			(size 0.1524 0.1524)
			(layers "F.Cu" "F.Mask" "F.Paste")
			(net "P3V3_STBY")
			(options
				(clearance outline)
				(anchor circle)
			)
			(primitives
				(gr_poly
					(pts
						(arc
							(start 0.3048 -0.2032)
							(mid 0.275042 -0.275042)
							(end 0.2032 -0.3048)
						)
						(arc
							(start -0.2032 -0.3048)
							(mid -0.275042 -0.275042)
							(end -0.3048 -0.2032)
						)
						(arc
							(start -0.3048 0.2032)
							(mid -0.275042 0.275042)
							(end -0.2032 0.3048)
						)
						(arc
							(start 0.2032 0.3048)
							(mid 0.275042 0.275042)
							(end 0.3048 0.2032)
						)
					)
					(width 0)
					(fill yes)
				)
			)
		)
		(pad "2" smd custom
			(at 0 0.4445 180)
			(size 0.1524 0.1524)
			(layers "F.Cu" "F.Mask" "F.Paste")
			(net "GND")
			(options
				(clearance outline)
				(anchor circle)
			)
			(primitives
				(gr_poly
					(pts
						(arc
							(start 0.3048 -0.2032)
							(mid 0.275042 -0.275042)
							(end 0.2032 -0.3048)
						)
						(arc
							(start -0.2032 -0.3048)
							(mid -0.275042 -0.275042)
							(end -0.3048 -0.2032)
						)
						(arc
							(start -0.3048 0.2032)
							(mid -0.275042 0.275042)
							(end -0.2032 0.3048)
						)
						(arc
							(start 0.2032 0.3048)
							(mid 0.275042 0.275042)
							(end 0.3048 0.2032)
						)
					)
					(width 0)
					(fill yes)
				)
			)
		)
	)
)
